# S9S_MB_2U (Grand Teton) — schematic netlist excerpt (pin names and nets, part order shuffled) for the footprints in the layout excerpt that follows; sources: Cadence DE-HDL packaged netlist, KiCad conversion of 03242023_DA0F0TMBIJ0_F0T_Motherboard_J_brd_V01_OCP.brd

PC189_P0_1  Q_CAP  3300PF 50V 10% X7R  pkg 0402  page 275 : A = SW_P12V_PVCCINFAON_CPU0_FLT ; B = GND

(kicad_pcb
	(version 20260206)
	(generator "pcbnew")
	(generator_version "10.0")
	(general
		(thickness 1.6)
		(legacy_teardrops no)
	)
	(paper "A4")
	(title_block
		(title "03242023_DA0F0TMBIJ0_F0T_Motherboard_J_brd_V01_OCP.brd")
		(comment 1 "Grand Teton / footprints 1286-1286 of 6105")
	)
	(layers
		(0 "F.Cu" signal "TOP")
		(4 "In1.Cu" signal "GND")
		(6 "In2.Cu" signal "IN1")
		(8 "In3.Cu" signal "GND1")
		(10 "In4.Cu" signal "IN2")
		(12 "In5.Cu" signal "GND2")
		(14 "In6.Cu" signal "IN3")
		(16 "In7.Cu" signal "GND3")
		(18 "In8.Cu" signal "VCC")
		(20 "In9.Cu" signal "VCC1")
		(22 "In10.Cu" signal "GND4")
		(24 "In11.Cu" signal "IN4")
		(26 "In12.Cu" signal "GND5")
		(28 "In13.Cu" signal "IN5")
		(30 "In14.Cu" signal "GND6")
		(32 "In15.Cu" signal "IN6")
		(34 "In16.Cu" signal "GND7")
		(2 "B.Cu" signal "BOTTOM")
		(9 "F.Adhes" user "F.Adhesive")
		(11 "B.Adhes" user "B.Adhesive")
		(13 "F.Paste" user "Package Geometry/Pastemask Top")
		(15 "B.Paste" user "Package Geometry/Pastemask Bottom")
		(5 "F.SilkS" user "Ref Des/Silkscreen Top")
		(7 "B.SilkS" user "Ref Des/Silkscreen Bottom")
		(1 "F.Mask" user "Board Geometry/Soldermask Top")
		(3 "B.Mask" user "Board Geometry/Soldermask Bottom")
		(17 "Dwgs.User" user "User.Drawings")
		(19 "Cmts.User" user "User.Comments")
		(21 "Eco1.User" user "User.Eco1")
		(23 "Eco2.User" user "User.Eco2")
		(25 "Edge.Cuts" user "Board Geometry/Outline")
		(27 "Margin" user)
		(31 "F.CrtYd" user "Package Geometry/Place Bound Top")
		(29 "B.CrtYd" user "Package Geometry/Place Bound Bottom")
		(35 "F.Fab" user "Ref Des/Assembly Top")
		(33 "B.Fab" user "Ref Des/Assembly Bottom")
	)
	(footprint ""
		(layer "F.Cu")
		(at 416.097974 -167.25265 180)
		(property "Reference" "PC189_P0_1"
			(at 0 0 180)
			(layer "F.SilkS")
			(hide yes)
			(effects
				(font
					(size 1.27 1.27)
				)
			)
		)
		(property "Value" ""
			(at 0 0 180)
			(layer "F.Fab")
			(effects
				(font
					(size 1.27 1.27)
				)
			)
		)
		(duplicate_pad_numbers_are_jumpers no)
		(fp_line
			(start 0.7874 0.4064)
			(end -0.7874 0.4064)
			(stroke
				(width 0.1524)
				(type default)
			)
			(layer "F.SilkS")
		)
		(fp_line
			(start 0.7874 -0.4064)
			(end 0.7874 0.4064)
			(stroke
				(width 0.1524)
				(type default)
			)
			(layer "F.SilkS")
		)
		(fp_line
			(start -0.7874 0.4064)
			(end -0.7874 -0.4064)
			(stroke
				(width 0.1524)
				(type default)
			)
			(layer "F.SilkS")
		)
		(fp_line
			(start -0.7874 -0.4064)
			(end 0.7874 -0.4064)
			(stroke
				(width 0.1524)
				(type default)
			)
			(layer "F.SilkS")
		)
		(fp_line
			(start 0.67945 0.3048)
			(end 0.120396 0.3048)
			(stroke
				(width 0.1)
				(type default)
			)
			(layer "F.Fab")
		)
		(fp_line
			(start 0.67945 -0.3048)
			(end 0.67945 0.3048)
			(stroke
				(width 0.1)
				(type default)
			)
			(layer "F.Fab")
		)
		(fp_line
			(start 0.12065 -0.2794)
			(end 0.12065 -0.3048)
			(stroke
				(width 0.1)
				(type default)
			)
			(layer "F.Fab")
		)
		(fp_line
			(start 0.12065 -0.3048)
			(end 0.67945 -0.3048)
			(stroke
				(width 0.1)
				(type default)
			)
			(layer "F.Fab")
		)
		(fp_line
			(start 0.120396 0.3048)
			(end 0.120396 0.2794)
			(stroke
				(width 0.1)
				(type default)
			)
			(layer "F.Fab")
		)
		(fp_line
			(start 0.120396 0.2794)
			(end -0.12065 0.2794)
			(stroke
				(width 0.1)
				(type default)
			)
			(layer "F.Fab")
		)
		(fp_line
			(start -0.12065 0.3048)
			(end -0.67945 0.3048)
			(stroke
				(width 0.1)
				(type default)
			)
			(layer "F.Fab")
		)
		(fp_line
			(start -0.12065 0.2794)
			(end -0.12065 0.3048)
			(stroke
				(width 0.1)
				(type default)
			)
			(layer "F.Fab")
		)
		(fp_line
			(start -0.12065 -0.2794)
			(end 0.12065 -0.2794)
			(stroke
				(width 0.1)
				(type default)
			)
			(layer "F.Fab")
		)
		(fp_line
			(start -0.12065 -0.305054)
			(end -0.12065 -0.2794)
			(stroke
				(width 0.1)
				(type default)
			)
			(layer "F.Fab")
		)
		(fp_line
			(start -0.67945 0.3048)
			(end -0.67945 -0.305054)
			(stroke
				(width 0.1)
				(type default)
			)
			(layer "F.Fab")
		)
		(fp_line
			(start -0.67945 -0.305054)
			(end -0.12065 -0.305054)
			(stroke
				(width 0.1)
				(type default)
			)
			(layer "F.Fab")
		)
		(pad "1" smd circle
			(at -0.40005 0 180)
			(size 0 0)
			(layers "F.Cu" "F.Mask" "F.Paste")
			(net "SW_P12V_PVCCINFAON_CPU0_FLT")
		)
		(pad "2" smd circle
			(at 0.40005 0 180)
			(size 0 0)
			(layers "F.Cu" "F.Mask" "F.Paste")
			(net "GND")
		)
	)
)
